G04 #@! TF.GenerationSoftware,KiCad,Pcbnew,(5.0.1)-3*
G04 #@! TF.CreationDate,2019-04-10T15:36:06+02:00*
G04 #@! TF.ProjectId,discovery,646973636F766572792E6B696361645F,rev?*
G04 #@! TF.SameCoordinates,PX4c4640PY8a48028*
G04 #@! TF.FileFunction,Paste,Bot*
G04 #@! TF.FilePolarity,Positive*
%FSLAX46Y46*%
G04 Gerber Fmt 4.6, Leading zero omitted, Abs format (unit mm)*
%MOMM*%
%LPD*%
G01*
G04 APERTURE LIST*
G04 APERTURE END LIST*
M02*
